# T6G (Grand Teton) — schematic netlist excerpt (pin names and nets, part order shuffled) for the footprints in the layout excerpt that follows; sources: Cadence DE-HDL packaged netlist, KiCad conversion of 04192023_DAF0TMB3IC0_F0TG_MB_C_brd_V02_OCP.brd

L32  Q_INDUCTOR  BLM15PD121SN1D/1300MA IND  pkg SMLF  page 345 : \1\ = P1V8_CPU1_RT_1D ; \2\ = P1V8_CPU1_RT2_1A_1D
R1929  Q_RES  10K 1% CHIP  pkg 0402LF  page 131 : A = GND ; B = OCP_SFF_AUX_PWR_EN

(kicad_pcb
	(version 20260206)
	(generator "pcbnew")
	(generator_version "10.0")
	(general
		(thickness 1.6)
		(legacy_teardrops no)
	)
	(paper "A4")
	(title_block
		(title "04192023_DAF0TMB3IC0_F0TG_MB_C_brd_V02_OCP.brd")
		(comment 1 "Grand Teton / footprints 2824-2825 of 8354")
	)
	(layers
		(0 "F.Cu" signal "TOP")
		(4 "In1.Cu" signal "GND")
		(6 "In2.Cu" signal "IN1")
		(8 "In3.Cu" signal "GND1")
		(10 "In4.Cu" signal "IN2")
		(12 "In5.Cu" signal "GND2")
		(14 "In6.Cu" signal "IN3")
		(16 "In7.Cu" signal "GND3")
		(18 "In8.Cu" signal "VCC")
		(20 "In9.Cu" signal "VCC1")
		(22 "In10.Cu" signal "GND4")
		(24 "In11.Cu" signal "IN4")
		(26 "In12.Cu" signal "GND5")
		(28 "In13.Cu" signal "IN5")
		(30 "In14.Cu" signal "GND6")
		(32 "In15.Cu" signal "IN6")
		(34 "In16.Cu" signal "GND7")
		(2 "B.Cu" signal "BOTTOM")
		(9 "F.Adhes" user "F.Adhesive")
		(11 "B.Adhes" user "B.Adhesive")
		(13 "F.Paste" user "Package Geometry/Pastemask Top")
		(15 "B.Paste" user "Package Geometry/Pastemask Bottom")
		(5 "F.SilkS" user "Ref Des/Silkscreen Top")
		(7 "B.SilkS" user "Ref Des/Silkscreen Bottom")
		(1 "F.Mask" user "Board Geometry/Soldermask Top")
		(3 "B.Mask" user "Board Geometry/Soldermask Bottom")
		(17 "Dwgs.User" user "User.Drawings")
		(19 "Cmts.User" user "User.Comments")
		(21 "Eco1.User" user "User.Eco1")
		(23 "Eco2.User" user "User.Eco2")
		(25 "Edge.Cuts" user "Board Geometry/Outline")
		(27 "Margin" user)
		(31 "F.CrtYd" user "Package Geometry/Place Bound Top")
		(29 "B.CrtYd" user "Package Geometry/Place Bound Bottom")
		(35 "F.Fab" user "Ref Des/Assembly Top")
		(33 "B.Fab" user "Ref Des/Assembly Bottom")
	)
	(footprint ""
		(layer "F.Cu")
		(at 434.796692 -19.625818 -90)
		(property "Reference" "R1929"
			(at 0 0 270)
			(layer "F.SilkS")
			(hide yes)
			(effects
				(font
					(size 1.27 1.27)
				)
			)
		)
		(property "Value" ""
			(at 0 0 270)
			(layer "F.Fab")
			(effects
				(font
					(size 1.27 1.27)
				)
			)
		)
		(duplicate_pad_numbers_are_jumpers no)
		(fp_line
			(start -0.7874 0.4064)
			(end -0.7874 -0.4064)
			(stroke
				(width 0.1524)
				(type default)
			)
			(layer "F.SilkS")
		)
		(fp_line
			(start 0.7874 0.4064)
			(end -0.7874 0.4064)
			(stroke
				(width 0.1524)
				(type default)
			)
			(layer "F.SilkS")
		)
		(fp_line
			(start -0.7874 -0.4064)
			(end 0.7874 -0.4064)
			(stroke
				(width 0.1524)
				(type default)
			)
			(layer "F.SilkS")
		)
		(fp_line
			(start 0.7874 -0.4064)
			(end 0.7874 0.4064)
			(stroke
				(width 0.1524)
				(type default)
			)
			(layer "F.SilkS")
		)
		(fp_line
			(start -0.67945 0.3048)
			(end -0.67945 -0.305054)
			(stroke
				(width 0.1)
				(type default)
			)
			(layer "F.Fab")
		)
		(fp_line
			(start -0.12065 0.3048)
			(end -0.67945 0.3048)
			(stroke
				(width 0.1)
				(type default)
			)
			(layer "F.Fab")
		)
		(fp_line
			(start 0.120396 0.3048)
			(end 0.120396 0.2794)
			(stroke
				(width 0.1)
				(type default)
			)
			(layer "F.Fab")
		)
		(fp_line
			(start 0.67945 0.3048)
			(end 0.120396 0.3048)
			(stroke
				(width 0.1)
				(type default)
			)
			(layer "F.Fab")
		)
		(fp_line
			(start -0.12065 0.2794)
			(end -0.12065 0.3048)
			(stroke
				(width 0.1)
				(type default)
			)
			(layer "F.Fab")
		)
		(fp_line
			(start 0.120396 0.2794)
			(end -0.12065 0.2794)
			(stroke
				(width 0.1)
				(type default)
			)
			(layer "F.Fab")
		)
		(fp_line
			(start -0.12065 -0.2794)
			(end 0.12065 -0.2794)
			(stroke
				(width 0.1)
				(type default)
			)
			(layer "F.Fab")
		)
		(fp_line
			(start 0.12065 -0.2794)
			(end 0.12065 -0.3048)
			(stroke
				(width 0.1)
				(type default)
			)
			(layer "F.Fab")
		)
		(fp_line
			(start 0.12065 -0.3048)
			(end 0.67945 -0.3048)
			(stroke
				(width 0.1)
				(type default)
			)
			(layer "F.Fab")
		)
		(fp_line
			(start 0.67945 -0.3048)
			(end 0.67945 0.3048)
			(stroke
				(width 0.1)
				(type default)
			)
			(layer "F.Fab")
		)
		(fp_line
			(start -0.67945 -0.305054)
			(end -0.12065 -0.305054)
			(stroke
				(width 0.1)
				(type default)
			)
			(layer "F.Fab")
		)
		(fp_line
			(start -0.12065 -0.305054)
			(end -0.12065 -0.2794)
			(stroke
				(width 0.1)
				(type default)
			)
			(layer "F.Fab")
		)
		(pad "1" smd circle
			(at -0.40005 0 270)
			(size 0 0)
			(layers "F.Cu" "F.Mask" "F.Paste")
			(net "GND")
		)
		(pad "2" smd circle
			(at 0.40005 0 270)
			(size 0 0)
			(layers "F.Cu" "F.Mask" "F.Paste")
			(net "OCP_SFF_AUX_PWR_EN")
		)
	)
	(footprint ""
		(layer "F.Cu")
		(at 171.26966 -388.753604 180)
		(property "Reference" "L32"
			(at 0 0 180)
			(layer "F.SilkS")
			(hide yes)
			(effects
				(font
					(size 1.27 1.27)
				)
			)
		)
		(property "Value" ""
			(at 0 0 180)
			(layer "F.Fab")
			(effects
				(font
					(size 1.27 1.27)
				)
			)
		)
		(duplicate_pad_numbers_are_jumpers no)
		(fp_line
			(start 0.762 0.381)
			(end -0.762 0.381)
			(stroke
				(width 0.1524)
				(type default)
			)
			(layer "F.SilkS")
		)
		(fp_line
			(start 0.762 -0.381)
			(end 0.762 0.381)
			(stroke
				(width 0.1524)
				(type default)
			)
			(layer "F.SilkS")
		)
		(fp_line
			(start -0.762 0.381)
			(end -0.762 -0.381)
			(stroke
				(width 0.1524)
				(type default)
			)
			(layer "F.SilkS")
		)
		(fp_line
			(start -0.762 -0.381)
			(end 0.762 -0.381)
			(stroke
				(width 0.1524)
				(type default)
			)
			(layer "F.SilkS")
		)
		(fp_line
			(start 0.680466 0.306324)
			(end 0.118364 0.306324)
			(stroke
				(width 0.1)
				(type default)
			)
			(layer "F.Fab")
		)
		(fp_line
			(start 0.680466 -0.306324)
			(end 0.680466 0.306324)
			(stroke
				(width 0.1)
				(type default)
			)
			(layer "F.Fab")
		)
		(fp_line
			(start 0.118872 -0.2794)
			(end 0.118872 -0.306324)
			(stroke
				(width 0.1)
				(type default)
			)
			(layer "F.Fab")
		)
		(fp_line
			(start 0.118872 -0.306324)
			(end 0.680466 -0.306324)
			(stroke
				(width 0.1)
				(type default)
			)
			(layer "F.Fab")
		)
		(fp_line
			(start 0.118364 0.306324)
			(end 0.118364 0.2794)
			(stroke
				(width 0.1)
				(type default)
			)
			(layer "F.Fab")
		)
		(fp_line
			(start 0.118364 0.2794)
			(end -0.119634 0.2794)
			(stroke
				(width 0.1)
				(type default)
			)
			(layer "F.Fab")
		)
		(fp_line
			(start -0.118364 -0.2794)
			(end 0.118872 -0.2794)
			(stroke
				(width 0.1)
				(type default)
			)
			(layer "F.Fab")
		)
		(fp_line
			(start -0.118364 -0.307086)
			(end -0.118364 -0.2794)
			(stroke
				(width 0.1)
				(type default)
			)
			(layer "F.Fab")
		)
		(fp_line
			(start -0.119634 0.30607)
			(end -0.681736 0.30607)
			(stroke
				(width 0.1)
				(type default)
			)
			(layer "F.Fab")
		)
		(fp_line
			(start -0.119634 0.2794)
			(end -0.119634 0.30607)
			(stroke
				(width 0.1)
				(type default)
			)
			(layer "F.Fab")
		)
		(fp_line
			(start -0.681736 0.30607)
			(end -0.681736 -0.307086)
			(stroke
				(width 0.1)
				(type default)
			)
			(layer "F.Fab")
		)
		(fp_line
			(start -0.681736 -0.307086)
			(end -0.118364 -0.307086)
			(stroke
				(width 0.1)
				(type default)
			)
			(layer "F.Fab")
		)
		(pad "1" smd rect
			(at -0.40005 0)
			(size 0.4572 0.508)
			(layers "F.Cu" "F.Mask" "F.Paste")
			(net "P1V8_CPU1_RT_1D")
		)
		(pad "2" smd rect
			(at 0.40005 0)
			(size 0.4572 0.508)
			(layers "F.Cu" "F.Mask" "F.Paste")
			(net "P1V8_CPU1_RT2_1A_1D")
		)
	)
)
